FILE NAME: R4006-B0001-02_R01_FAB_TTM.ZIP

      ITEM DESCRIPTION                                 FILE NAME
      GERBER FORMAT INFORMATION                        art_param.txt
      GERBER FORMAT INFORMATION                        art_aper.txt
                                                       RS274X  5.5A

      GERBER ARTWORK FILES OF THE FOLLOWING
      ARTWORK LAYER # 01 - COMPONENT SIDE              R4006-B0001-02_R01_L01.art
      ARTWORK LAYER # 02 - GND PLANE                   R4006-B0001-02_R01_L02.art
      ARTWORK LAYER # 03 - SIGNAL LAYER                R4006-B0001-02_R01_L03.art
      ARTWORK LAYER # 04 - GND PLANE                   R4006-B0001-02_R01_L04.art
      ARTWORK LAYER # 05 - POWER PLANE                 R4006-B0001-02_R01_L05.art
      ARTWORK LAYER # 06 - POWER PLANE                 R4006-B0001-02_R01_L06.art
      ARTWORK LAYER # 07 - GND PLANE                   R4006-B0001-02_R01_L07.art
      ARTWORK LAYER # 08 - SIGNAL LAYER                R4006-B0001-02_R01_L08.art
      ARTWORK LAYER # 09 - GND PLANE                   R4006-B0001-02_R01_L09.art
      ARTWORK LAYER # 10 - SOLDER SIDE                 R4006-B0001-02_R01_L10.art


      ARTWORK BACKDRILL FILE                           R4006-B0001-02_R01_bd_1-7.art
      ARTWORK BACKDRILL FILE                           R4006-B0001-02_R01_bd_10-9.art


      SOLDERPASTE PRIMARY TOP                          R4006-B0001-02_R01_TPM.art
      SOLDERPASTE SECONDARY BOTTOM                     R4006-B0001-02_R01_BPM.art
      SOLDERMASK PRIMARY TOP                           R4006-B0001-02_R01_TSM.art
      SOLDERMASK SECONDARY BOTTOM                      R4006-B0001-02_R01_BSM.art
      SILKSCREEN PRIMARY TOP                           R4006-B0001-02_R01_TSS.art
      SILKSCREEN SECONDARY BOTTOM                      R4006-B0001-02_R01_BSS.art
      BOARD OUTLINE                                    R4006-B0001-02_R01_OTL.art
      FABRICATION DRAWING GERBER FORMAT                R4006-B0001-02_R01_FAB.art


      N/C DRILL DATA                                   R4006-B0001-02_R01-1-10.drl
      N/C ROUTE                                        R4006-B0001-02_R01_1-10.rou

      BACKDRILL DRILL DATA                             R4006-B0001-02_R01-bd-1-7.drl
      BACKDRILL DRILL DATA                             R4006-B0001-02_R01-bd-10-9.drl

      N/C DRILL/ROUTE PARAMETER FILE                   nc_param.txt
      N/C DRILL/ROUTE PARAMETER FILE                   ncdrill.log
      N/C ROUTE                                        ncroute.log
      IPC NET LIST FILE                                R4006-B0001-02_R01_NET.ipc
      Slot Hole Report                                 Slot_Hole_Report.txt

      FABRICATION DRAWING PDF FORMAT                   R4006-B0001-02_R01_FAB.pdf                                       

      Stack up                                         R4006-B0001_FB_Timing card _Stackup_10L_1.57mm_TU863+_V1.1_09222021.pdf
      PANEL DRAWING PDF FILE                           R4006-B0001-02-PN-E1.pdf
                                                       R4006-B0001-02-PN-E1.dxf
                            
